(kicad_pcb
	(version 20260206)
	(generator "pcbnew")
	(generator_version "10.0")
	(general
		(thickness 1.6)
		(legacy_teardrops no)
	)
	(paper "A4")
	(title_block
		(title "01162023_DA0F0TEBIF0_F0T_Expander_BD_F_brd_V02_OCP.brd")
		(comment 1 "Grand Teton / footprints 7178-7187 of 9728")
	)
	(layers
		(0 "F.Cu" signal "TOP")
		(4 "In1.Cu" signal "GND")
		(6 "In2.Cu" signal "VCC")
		(8 "In3.Cu" signal "VCC1")
		(10 "In4.Cu" signal "GND1")
		(12 "In5.Cu" signal "IN1")
		(14 "In6.Cu" signal "GND2")
		(16 "In7.Cu" signal "IN2")
		(18 "In8.Cu" signal "GND3")
		(20 "In9.Cu" signal "IN3")
		(22 "In10.Cu" signal "GND4")
		(24 "In11.Cu" signal "IN4")
		(26 "In12.Cu" signal "GND5")
		(28 "In13.Cu" signal "IN5")
		(30 "In14.Cu" signal "GND6")
		(32 "In15.Cu" signal "IN6")
		(34 "In16.Cu" signal "GND7")
		(2 "B.Cu" signal "BOTTOM")
		(9 "F.Adhes" user "F.Adhesive")
		(11 "B.Adhes" user "B.Adhesive")
		(13 "F.Paste" user "Package Geometry/Pastemask Top")
		(15 "B.Paste" user "Package Geometry/Pastemask Bottom")
		(5 "F.SilkS" user "Ref Des/Silkscreen Top")
		(7 "B.SilkS" user "Ref Des/Silkscreen Bottom")
		(1 "F.Mask" user "Board Geometry/Soldermask Top")
		(3 "B.Mask" user "Board Geometry/Soldermask Bottom")
		(17 "Dwgs.User" user "User.Drawings")
		(19 "Cmts.User" user "User.Comments")
		(21 "Eco1.User" user "User.Eco1")
		(23 "Eco2.User" user "User.Eco2")
		(25 "Edge.Cuts" user "Board Geometry/Outline")
		(27 "Margin" user)
		(31 "F.CrtYd" user "Package Geometry/Place Bound Top")
		(29 "B.CrtYd" user "Package Geometry/Place Bound Bottom")
		(35 "F.Fab" user "Ref Des/Assembly Top")
		(33 "B.Fab" user "Ref Des/Assembly Bottom")
	)
	(footprint ""
		(layer "B.Cu")
		(at 276.649688 -293.04996)
		(property "Reference" "C3354"
			(at 0 0 0)
			(layer "B.SilkS")
			(hide yes)
			(effects
				(font
					(size 1.27 1.27)
				)
				(justify mirror)
			)
		)
		(property "Value" ""
			(at 0 0 0)
			(layer "B.Fab")
			(effects
				(font
					(size 1.27 1.27)
				)
				(justify mirror)
			)
		)
		(duplicate_pad_numbers_are_jumpers no)
		(fp_line
			(start -0.299974 -0.150114)
			(end -0.299974 0.150114)
			(stroke
				(width 0.1)
				(type default)
			)
			(layer "B.Fab")
		)
		(fp_line
			(start -0.299974 0.150114)
			(end 0.299974 0.150114)
			(stroke
				(width 0.1)
				(type default)
			)
			(layer "B.Fab")
		)
		(fp_line
			(start 0.299974 -0.150114)
			(end -0.299974 -0.150114)
			(stroke
				(width 0.1)
				(type default)
			)
			(layer "B.Fab")
		)
		(fp_line
			(start 0.299974 0.150114)
			(end 0.299974 -0.150114)
			(stroke
				(width 0.1)
				(type default)
			)
			(layer "B.Fab")
		)
		(pad "1" smd rect
			(at 0.2667 0 180)
			(size 0.3048 0.381)
			(layers "B.Cu" "B.Mask" "B.Paste")
			(net "P1V8_PEX")
		)
		(pad "2" smd rect
			(at -0.2667 0 180)
			(size 0.3048 0.381)
			(layers "B.Cu" "B.Mask" "B.Paste")
			(net "GND")
		)
	)
	(footprint ""
		(layer "B.Cu")
		(at 63.924942 -297.79976 90)
		(property "Reference" "C1116"
			(at 0 0 90)
			(layer "B.SilkS")
			(hide yes)
			(effects
				(font
					(size 1.27 1.27)
				)
				(justify mirror)
			)
		)
		(property "Value" ""
			(at 0 0 90)
			(layer "B.Fab")
			(effects
				(font
					(size 1.27 1.27)
				)
				(justify mirror)
			)
		)
		(duplicate_pad_numbers_are_jumpers no)
		(fp_line
			(start 0.299974 -0.150114)
			(end -0.299974 -0.150114)
			(stroke
				(width 0.1)
				(type default)
			)
			(layer "B.Fab")
		)
		(fp_line
			(start -0.299974 -0.150114)
			(end -0.299974 0.150114)
			(stroke
				(width 0.1)
				(type default)
			)
			(layer "B.Fab")
		)
		(fp_line
			(start 0.299974 0.150114)
			(end 0.299974 -0.150114)
			(stroke
				(width 0.1)
				(type default)
			)
			(layer "B.Fab")
		)
		(fp_line
			(start -0.299974 0.150114)
			(end 0.299974 0.150114)
			(stroke
				(width 0.1)
				(type default)
			)
			(layer "B.Fab")
		)
		(pad "1" smd rect
			(at 0.2667 0 270)
			(size 0.3048 0.381)
			(layers "B.Cu" "B.Mask" "B.Paste")
			(net "P0V8_PEX0")
		)
		(pad "2" smd rect
			(at -0.2667 0 270)
			(size 0.3048 0.381)
			(layers "B.Cu" "B.Mask" "B.Paste")
			(net "GND")
		)
	)
	(footprint ""
		(layer "B.Cu")
		(at 397.85544 -156.0576)
		(property "Reference" "R334"
			(at 0 0 0)
			(layer "B.SilkS")
			(hide yes)
			(effects
				(font
					(size 1.27 1.27)
				)
				(justify mirror)
			)
		)
		(property "Value" ""
			(at 0 0 0)
			(layer "B.Fab")
			(effects
				(font
					(size 1.27 1.27)
				)
				(justify mirror)
			)
		)
		(duplicate_pad_numbers_are_jumpers no)
		(fp_line
			(start -0.7874 -0.4064)
			(end -0.7874 0.4064)
			(stroke
				(width 0.1524)
				(type default)
			)
			(layer "B.SilkS")
		)
		(fp_line
			(start -0.7874 0.4064)
			(end 0.7874 0.4064)
			(stroke
				(width 0.1524)
				(type default)
			)
			(layer "B.SilkS")
		)
		(fp_line
			(start 0.7874 -0.4064)
			(end -0.7874 -0.4064)
			(stroke
				(width 0.1524)
				(type default)
			)
			(layer "B.SilkS")
		)
		(fp_line
			(start 0.7874 0.4064)
			(end 0.7874 -0.4064)
			(stroke
				(width 0.1524)
				(type default)
			)
			(layer "B.SilkS")
		)
		(fp_line
			(start -0.67945 -0.3048)
			(end -0.67945 0.3048)
			(stroke
				(width 0.1)
				(type default)
			)
			(layer "B.Fab")
		)
		(fp_line
			(start -0.67945 0.3048)
			(end -0.120396 0.3048)
			(stroke
				(width 0.1)
				(type default)
			)
			(layer "B.Fab")
		)
		(fp_line
			(start -0.12065 -0.3048)
			(end -0.67945 -0.3048)
			(stroke
				(width 0.1)
				(type default)
			)
			(layer "B.Fab")
		)
		(fp_line
			(start -0.12065 -0.2794)
			(end -0.12065 -0.3048)
			(stroke
				(width 0.1)
				(type default)
			)
			(layer "B.Fab")
		)
		(fp_line
			(start -0.120396 0.2794)
			(end 0.12065 0.2794)
			(stroke
				(width 0.1)
				(type default)
			)
			(layer "B.Fab")
		)
		(fp_line
			(start -0.120396 0.3048)
			(end -0.120396 0.2794)
			(stroke
				(width 0.1)
				(type default)
			)
			(layer "B.Fab")
		)
		(fp_line
			(start 0.12065 -0.305054)
			(end 0.12065 -0.2794)
			(stroke
				(width 0.1)
				(type default)
			)
			(layer "B.Fab")
		)
		(fp_line
			(start 0.12065 -0.2794)
			(end -0.12065 -0.2794)
			(stroke
				(width 0.1)
				(type default)
			)
			(layer "B.Fab")
		)
		(fp_line
			(start 0.12065 0.2794)
			(end 0.12065 0.3048)
			(stroke
				(width 0.1)
				(type default)
			)
			(layer "B.Fab")
		)
		(fp_line
			(start 0.12065 0.3048)
			(end 0.67945 0.3048)
			(stroke
				(width 0.1)
				(type default)
			)
			(layer "B.Fab")
		)
		(fp_line
			(start 0.67945 -0.305054)
			(end 0.12065 -0.305054)
			(stroke
				(width 0.1)
				(type default)
			)
			(layer "B.Fab")
		)
		(fp_line
			(start 0.67945 0.3048)
			(end 0.67945 -0.305054)
			(stroke
				(width 0.1)
				(type default)
			)
			(layer "B.Fab")
		)
		(pad "1" smd circle
			(at 0.40005 0 180)
			(size 0 0)
			(layers "B.Cu" "B.Mask" "B.Paste")
			(net "NIC6_SLOT_ID1")
		)
		(pad "2" smd circle
			(at -0.40005 0 180)
			(size 0 0)
			(layers "B.Cu" "B.Mask" "B.Paste")
			(net "GND")
		)
	)
	(footprint ""
		(layer "B.Cu")
		(at 223.533716 -197.789292 -90)
		(property "Reference" "R1025"
			(at 0 0 90)
			(layer "B.SilkS")
			(hide yes)
			(effects
				(font
					(size 1.27 1.27)
				)
				(justify mirror)
			)
		)
		(property "Value" ""
			(at 0 0 90)
			(layer "B.Fab")
			(effects
				(font
					(size 1.27 1.27)
				)
				(justify mirror)
			)
		)
		(duplicate_pad_numbers_are_jumpers no)
		(fp_line
			(start -0.7874 0.4064)
			(end 0.7874 0.4064)
			(stroke
				(width 0.1524)
				(type default)
			)
			(layer "B.SilkS")
		)
		(fp_line
			(start 0.7874 0.4064)
			(end 0.7874 -0.4064)
			(stroke
				(width 0.1524)
				(type default)
			)
			(layer "B.SilkS")
		)
		(fp_line
			(start -0.7874 -0.4064)
			(end -0.7874 0.4064)
			(stroke
				(width 0.1524)
				(type default)
			)
			(layer "B.SilkS")
		)
		(fp_line
			(start 0.7874 -0.4064)
			(end -0.7874 -0.4064)
			(stroke
				(width 0.1524)
				(type default)
			)
			(layer "B.SilkS")
		)
		(fp_line
			(start -0.67945 0.3048)
			(end -0.120396 0.3048)
			(stroke
				(width 0.1)
				(type default)
			)
			(layer "B.Fab")
		)
		(fp_line
			(start -0.120396 0.3048)
			(end -0.120396 0.2794)
			(stroke
				(width 0.1)
				(type default)
			)
			(layer "B.Fab")
		)
		(fp_line
			(start 0.12065 0.3048)
			(end 0.67945 0.3048)
			(stroke
				(width 0.1)
				(type default)
			)
			(layer "B.Fab")
		)
		(fp_line
			(start 0.67945 0.3048)
			(end 0.67945 -0.305054)
			(stroke
				(width 0.1)
				(type default)
			)
			(layer "B.Fab")
		)
		(fp_line
			(start -0.120396 0.2794)
			(end 0.12065 0.2794)
			(stroke
				(width 0.1)
				(type default)
			)
			(layer "B.Fab")
		)
		(fp_line
			(start 0.12065 0.2794)
			(end 0.12065 0.3048)
			(stroke
				(width 0.1)
				(type default)
			)
			(layer "B.Fab")
		)
		(fp_line
			(start -0.12065 -0.2794)
			(end -0.12065 -0.3048)
			(stroke
				(width 0.1)
				(type default)
			)
			(layer "B.Fab")
		)
		(fp_line
			(start 0.12065 -0.2794)
			(end -0.12065 -0.2794)
			(stroke
				(width 0.1)
				(type default)
			)
			(layer "B.Fab")
		)
		(fp_line
			(start -0.67945 -0.3048)
			(end -0.67945 0.3048)
			(stroke
				(width 0.1)
				(type default)
			)
			(layer "B.Fab")
		)
		(fp_line
			(start -0.12065 -0.3048)
			(end -0.67945 -0.3048)
			(stroke
				(width 0.1)
				(type default)
			)
			(layer "B.Fab")
		)
		(fp_line
			(start 0.12065 -0.305054)
			(end 0.12065 -0.2794)
			(stroke
				(width 0.1)
				(type default)
			)
			(layer "B.Fab")
		)
		(fp_line
			(start 0.67945 -0.305054)
			(end 0.12065 -0.305054)
			(stroke
				(width 0.1)
				(type default)
			)
			(layer "B.Fab")
		)
		(pad "1" smd circle
			(at 0.40005 0 90)
			(size 0 0)
			(layers "B.Cu" "B.Mask" "B.Paste")
			(net "SPI_BIC1_MISO_R")
		)
		(pad "2" smd circle
			(at -0.40005 0 90)
			(size 0 0)
			(layers "B.Cu" "B.Mask" "B.Paste")
			(net "SPI_BIC1_MISO_R5")
		)
	)
	(footprint ""
		(layer "B.Cu")
		(at 179.55006 -303.499774 -90)
		(property "Reference" "C3092"
			(at 0 0 90)
			(layer "B.SilkS")
			(hide yes)
			(effects
				(font
					(size 1.27 1.27)
				)
				(justify mirror)
			)
		)
		(property "Value" ""
			(at 0 0 90)
			(layer "B.Fab")
			(effects
				(font
					(size 1.27 1.27)
				)
				(justify mirror)
			)
		)
		(duplicate_pad_numbers_are_jumpers no)
		(fp_line
			(start -0.299974 0.150114)
			(end 0.299974 0.150114)
			(stroke
				(width 0.1)
				(type default)
			)
			(layer "B.Fab")
		)
		(fp_line
			(start 0.299974 0.150114)
			(end 0.299974 -0.150114)
			(stroke
				(width 0.1)
				(type default)
			)
			(layer "B.Fab")
		)
		(fp_line
			(start -0.299974 -0.150114)
			(end -0.299974 0.150114)
			(stroke
				(width 0.1)
				(type default)
			)
			(layer "B.Fab")
		)
		(fp_line
			(start 0.299974 -0.150114)
			(end -0.299974 -0.150114)
			(stroke
				(width 0.1)
				(type default)
			)
			(layer "B.Fab")
		)
		(pad "1" smd rect
			(at 0.2667 0 90)
			(size 0.3048 0.381)
			(layers "B.Cu" "B.Mask" "B.Paste")
			(net "P1V25_PEX1")
		)
		(pad "2" smd rect
			(at -0.2667 0 90)
			(size 0.3048 0.381)
			(layers "B.Cu" "B.Mask" "B.Paste")
			(net "GND")
		)
	)
	(footprint ""
		(layer "B.Cu")
		(at 298.024804 -293.99992 -90)
		(property "Reference" "C1659"
			(at 0 0 90)
			(layer "B.SilkS")
			(hide yes)
			(effects
				(font
					(size 1.27 1.27)
				)
				(justify mirror)
			)
		)
		(property "Value" ""
			(at 0 0 90)
			(layer "B.Fab")
			(effects
				(font
					(size 1.27 1.27)
				)
				(justify mirror)
			)
		)
		(duplicate_pad_numbers_are_jumpers no)
		(fp_line
			(start -0.299974 0.150114)
			(end 0.299974 0.150114)
			(stroke
				(width 0.1)
				(type default)
			)
			(layer "B.Fab")
		)
		(fp_line
			(start 0.299974 0.150114)
			(end 0.299974 -0.150114)
			(stroke
				(width 0.1)
				(type default)
			)
			(layer "B.Fab")
		)
		(fp_line
			(start -0.299974 -0.150114)
			(end -0.299974 0.150114)
			(stroke
				(width 0.1)
				(type default)
			)
			(layer "B.Fab")
		)
		(fp_line
			(start 0.299974 -0.150114)
			(end -0.299974 -0.150114)
			(stroke
				(width 0.1)
				(type default)
			)
			(layer "B.Fab")
		)
		(pad "1" smd rect
			(at 0.2667 0 90)
			(size 0.3048 0.381)
			(layers "B.Cu" "B.Mask" "B.Paste")
			(net "P0V8_PEX2")
		)
		(pad "2" smd rect
			(at -0.2667 0 90)
			(size 0.3048 0.381)
			(layers "B.Cu" "B.Mask" "B.Paste")
			(net "GND")
		)
	)
	(footprint ""
		(layer "B.Cu")
		(at 167.200072 -303.499774 -90)
		(property "Reference" "C3079"
			(at 0 0 90)
			(layer "B.SilkS")
			(hide yes)
			(effects
				(font
					(size 1.27 1.27)
				)
				(justify mirror)
			)
		)
		(property "Value" ""
			(at 0 0 90)
			(layer "B.Fab")
			(effects
				(font
					(size 1.27 1.27)
				)
				(justify mirror)
			)
		)
		(duplicate_pad_numbers_are_jumpers no)
		(fp_line
			(start -0.299974 0.150114)
			(end 0.299974 0.150114)
			(stroke
				(width 0.1)
				(type default)
			)
			(layer "B.Fab")
		)
		(fp_line
			(start 0.299974 0.150114)
			(end 0.299974 -0.150114)
			(stroke
				(width 0.1)
				(type default)
			)
			(layer "B.Fab")
		)
		(fp_line
			(start -0.299974 -0.150114)
			(end -0.299974 0.150114)
			(stroke
				(width 0.1)
				(type default)
			)
			(layer "B.Fab")
		)
		(fp_line
			(start 0.299974 -0.150114)
			(end -0.299974 -0.150114)
			(stroke
				(width 0.1)
				(type default)
			)
			(layer "B.Fab")
		)
		(pad "1" smd rect
			(at 0.2667 0 90)
			(size 0.3048 0.381)
			(layers "B.Cu" "B.Mask" "B.Paste")
			(net "P1V25_PEX1")
		)
		(pad "2" smd rect
			(at -0.2667 0 90)
			(size 0.3048 0.381)
			(layers "B.Cu" "B.Mask" "B.Paste")
			(net "GND")
		)
	)
	(footprint ""
		(layer "B.Cu")
		(at 411.770322 -296.37482)
		(property "Reference" "C1888"
			(at 0 0 0)
			(layer "B.SilkS")
			(hide yes)
			(effects
				(font
					(size 1.27 1.27)
				)
				(justify mirror)
			)
		)
		(property "Value" ""
			(at 0 0 0)
			(layer "B.Fab")
			(effects
				(font
					(size 1.27 1.27)
				)
				(justify mirror)
			)
		)
		(duplicate_pad_numbers_are_jumpers no)
		(fp_line
			(start -0.299974 -0.150114)
			(end -0.299974 0.150114)
			(stroke
				(width 0.1)
				(type default)
			)
			(layer "B.Fab")
		)
		(fp_line
			(start -0.299974 0.150114)
			(end 0.299974 0.150114)
			(stroke
				(width 0.1)
				(type default)
			)
			(layer "B.Fab")
		)
		(fp_line
			(start 0.299974 -0.150114)
			(end -0.299974 -0.150114)
			(stroke
				(width 0.1)
				(type default)
			)
			(layer "B.Fab")
		)
		(fp_line
			(start 0.299974 0.150114)
			(end 0.299974 -0.150114)
			(stroke
				(width 0.1)
				(type default)
			)
			(layer "B.Fab")
		)
		(pad "1" smd rect
			(at 0.2667 0 180)
			(size 0.3048 0.381)
			(layers "B.Cu" "B.Mask" "B.Paste")
			(net "P0V8_PEX3")
		)
		(pad "2" smd rect
			(at -0.2667 0 180)
			(size 0.3048 0.381)
			(layers "B.Cu" "B.Mask" "B.Paste")
			(net "GND")
		)
	)
	(footprint ""
		(layer "B.Cu")
		(at 329.692 -222.4532 180)
		(property "Reference" "R4174"
			(at 0 0 0)
			(layer "B.SilkS")
			(hide yes)
			(effects
				(font
					(size 1.27 1.27)
				)
				(justify mirror)
			)
		)
		(property "Value" ""
			(at 0 0 0)
			(layer "B.Fab")
			(effects
				(font
					(size 1.27 1.27)
				)
				(justify mirror)
			)
		)
		(duplicate_pad_numbers_are_jumpers no)
		(fp_line
			(start 0.7874 0.4064)
			(end 0.7874 -0.4064)
			(stroke
				(width 0.1524)
				(type default)
			)
			(layer "B.SilkS")
		)
		(fp_line
			(start 0.7874 -0.4064)
			(end -0.7874 -0.4064)
			(stroke
				(width 0.1524)
				(type default)
			)
			(layer "B.SilkS")
		)
		(fp_line
			(start -0.7874 0.4064)
			(end 0.7874 0.4064)
			(stroke
				(width 0.1524)
				(type default)
			)
			(layer "B.SilkS")
		)
		(fp_line
			(start -0.7874 -0.4064)
			(end -0.7874 0.4064)
			(stroke
				(width 0.1524)
				(type default)
			)
			(layer "B.SilkS")
		)
		(fp_line
			(start 0.67945 0.3048)
			(end 0.67945 -0.305054)
			(stroke
				(width 0.1)
				(type default)
			)
			(layer "B.Fab")
		)
		(fp_line
			(start 0.67945 -0.305054)
			(end 0.12065 -0.305054)
			(stroke
				(width 0.1)
				(type default)
			)
			(layer "B.Fab")
		)
		(fp_line
			(start 0.12065 0.3048)
			(end 0.67945 0.3048)
			(stroke
				(width 0.1)
				(type default)
			)
			(layer "B.Fab")
		)
		(fp_line
			(start 0.12065 0.2794)
			(end 0.12065 0.3048)
			(stroke
				(width 0.1)
				(type default)
			)
			(layer "B.Fab")
		)
		(fp_line
			(start 0.12065 -0.2794)
			(end -0.12065 -0.2794)
			(stroke
				(width 0.1)
				(type default)
			)
			(layer "B.Fab")
		)
		(fp_line
			(start 0.12065 -0.305054)
			(end 0.12065 -0.2794)
			(stroke
				(width 0.1)
				(type default)
			)
			(layer "B.Fab")
		)
		(fp_line
			(start -0.120396 0.3048)
			(end -0.120396 0.2794)
			(stroke
				(width 0.1)
				(type default)
			)
			(layer "B.Fab")
		)
		(fp_line
			(start -0.120396 0.2794)
			(end 0.12065 0.2794)
			(stroke
				(width 0.1)
				(type default)
			)
			(layer "B.Fab")
		)
		(fp_line
			(start -0.12065 -0.2794)
			(end -0.12065 -0.3048)
			(stroke
				(width 0.1)
				(type default)
			)
			(layer "B.Fab")
		)
		(fp_line
			(start -0.12065 -0.3048)
			(end -0.67945 -0.3048)
			(stroke
				(width 0.1)
				(type default)
			)
			(layer "B.Fab")
		)
		(fp_line
			(start -0.67945 0.3048)
			(end -0.120396 0.3048)
			(stroke
				(width 0.1)
				(type default)
			)
			(layer "B.Fab")
		)
		(fp_line
			(start -0.67945 -0.3048)
			(end -0.67945 0.3048)
			(stroke
				(width 0.1)
				(type default)
			)
			(layer "B.Fab")
		)
		(pad "1" smd circle
			(at 0.40005 0)
			(size 0 0)
			(layers "B.Cu" "B.Mask" "B.Paste")
			(net "RST_PEX3_PERST_R_N")
		)
		(pad "2" smd circle
			(at -0.40005 0)
			(size 0 0)
			(layers "B.Cu" "B.Mask" "B.Paste")
			(net "RST_PEX3_PERST_N")
		)
	)
	(footprint ""
		(layer "B.Cu")
		(at 401.72005 -305.399948 -90)
		(property "Reference" "C3489"
			(at 0 0 90)
			(layer "B.SilkS")
			(hide yes)
			(effects
				(font
					(size 1.27 1.27)
				)
				(justify mirror)
			)
		)
		(property "Value" ""
			(at 0 0 90)
			(layer "B.Fab")
			(effects
				(font
					(size 1.27 1.27)
				)
				(justify mirror)
			)
		)
		(duplicate_pad_numbers_are_jumpers no)
		(fp_line
			(start -0.299974 0.150114)
			(end 0.299974 0.150114)
			(stroke
				(width 0.1)
				(type default)
			)
			(layer "B.Fab")
		)
		(fp_line
			(start 0.299974 0.150114)
			(end 0.299974 -0.150114)
			(stroke
				(width 0.1)
				(type default)
			)
			(layer "B.Fab")
		)
		(fp_line
			(start -0.299974 -0.150114)
			(end -0.299974 0.150114)
			(stroke
				(width 0.1)
				(type default)
			)
			(layer "B.Fab")
		)
		(fp_line
			(start 0.299974 -0.150114)
			(end -0.299974 -0.150114)
			(stroke
				(width 0.1)
				(type default)
			)
			(layer "B.Fab")
		)
		(pad "1" smd rect
			(at 0.2667 0 90)
			(size 0.3048 0.381)
			(layers "B.Cu" "B.Mask" "B.Paste")
			(net "P1V25_SERDES_VDDPLL_PEX3")
		)
		(pad "2" smd rect
			(at -0.2667 0 90)
			(size 0.3048 0.381)
			(layers "B.Cu" "B.Mask" "B.Paste")
			(net "GND")
		)
	)
)
